(kicad_pcb
	(version 20260206)
	(generator "pcbnew")
	(generator_version "10.0")
	(general
		(thickness 1.6)
		(legacy_teardrops no)
	)
	(paper "A4")
	(title_block
		(title "Bryce Canyon_SCC_16316-1_OCP.brd")
		(comment 1 "Bryce Canyon / footprints 213-219 of 1561")
	)
	(layers
		(0 "F.Cu" signal "TOP")
		(4 "In1.Cu" signal "L2GND")
		(6 "In2.Cu" signal "L3")
		(8 "In3.Cu" signal "L4VCC")
		(10 "In4.Cu" signal "L5VCC")
		(12 "In5.Cu" signal "L6")
		(14 "In6.Cu" signal "L7GND")
		(2 "B.Cu" signal "BOTTOM")
		(9 "F.Adhes" user "F.Adhesive")
		(11 "B.Adhes" user "B.Adhesive")
		(13 "F.Paste" user "Package Geometry/Pastemask Top")
		(15 "B.Paste" user "Package Geometry/Pastemask Bottom")
		(5 "F.SilkS" user "Ref Des/Silkscreen Top")
		(7 "B.SilkS" user "Ref Des/Silkscreen Bottom")
		(1 "F.Mask" user "Board Geometry/Soldermask Top")
		(3 "B.Mask" user "Board Geometry/Soldermask Bottom")
		(17 "Dwgs.User" user "User.Drawings")
		(19 "Cmts.User" user "User.Comments")
		(21 "Eco1.User" user "User.Eco1")
		(23 "Eco2.User" user "User.Eco2")
		(25 "Edge.Cuts" user "Board Geometry/Outline")
		(27 "Margin" user)
		(31 "F.CrtYd" user "Package Geometry/Place Bound Top")
		(29 "B.CrtYd" user "Package Geometry/Place Bound Bottom")
		(35 "F.Fab" user "Ref Des/Assembly Top")
		(33 "B.Fab" user "Ref Des/Assembly Bottom")
	)
	(footprint ""
		(layer "F.Cu")
		(at 94.234 -70.993 -90)
		(property "Reference" "R148"
			(at 0 0 270)
			(layer "F.SilkS")
			(hide yes)
			(effects
				(font
					(size 1.27 1.27)
				)
			)
		)
		(property "Value" "4K75R2F-1-GP"
			(at 0.064008 -3.993896 270)
			(unlocked yes)
			(layer "F.Fab")
			(hide yes)
			(effects
				(font
					(size 1.016 1.016)
					(thickness 0.1524)
				)
			)
		)
		(property "Device Type" "R402H16"
			(at 0.064008 -5.517896 270)
			(unlocked yes)
			(layer "F.Fab")
			(hide yes)
			(effects
				(font
					(size 1.016 1.016)
					(thickness 0.1524)
				)
			)
		)
		(duplicate_pad_numbers_are_jumpers no)
		(fp_line
			(start -0.508 -0.9398)
			(end -0.508 0.9398)
			(stroke
				(width 0.1524)
				(type default)
			)
			(layer "F.SilkS")
		)
		(fp_line
			(start 0.508 -0.9398)
			(end -0.508 -0.9398)
			(stroke
				(width 0.1524)
				(type default)
			)
			(layer "F.SilkS")
		)
		(fp_rect
			(start -0.508 0.9398)
			(end 0.508 -0.9398)
			(stroke
				(width 0)
				(type default)
			)
			(fill no)
			(layer "F.CrtYd")
		)
		(fp_rect
			(start -0.508 0.9398)
			(end 0.508 -0.9398)
			(stroke
				(width 0)
				(type default)
			)
			(fill no)
			(layer "F.Fab")
		)
		(pad "1" smd custom
			(at 0 -0.4445 270)
			(size 0.1397 0.1397)
			(layers "F.Cu" "F.Mask" "F.Paste")
			(net "LSI_SCAN_ENABLE")
			(options
				(clearance outline)
				(anchor circle)
			)
			(primitives
				(gr_poly
					(pts
						(arc
							(start -0.1778 -0.2794)
							(mid -0.249642 -0.249642)
							(end -0.2794 -0.1778)
						)
						(arc
							(start -0.2794 0.1778)
							(mid -0.249642 0.249642)
							(end -0.1778 0.2794)
						)
						(arc
							(start 0.1778 0.2794)
							(mid 0.249642 0.249642)
							(end 0.2794 0.1778)
						)
						(arc
							(start 0.2794 -0.1778)
							(mid 0.249642 -0.249642)
							(end 0.1778 -0.2794)
						)
					)
					(width 0)
					(fill yes)
				)
			)
		)
		(pad "2" smd custom
			(at 0 0.4445 270)
			(size 0.1397 0.1397)
			(layers "F.Cu" "F.Mask" "F.Paste")
			(net "P1V8_E")
			(options
				(clearance outline)
				(anchor circle)
			)
			(primitives
				(gr_poly
					(pts
						(arc
							(start -0.1778 -0.2794)
							(mid -0.249642 -0.249642)
							(end -0.2794 -0.1778)
						)
						(arc
							(start -0.2794 0.1778)
							(mid -0.249642 0.249642)
							(end -0.1778 0.2794)
						)
						(arc
							(start 0.1778 0.2794)
							(mid 0.249642 0.249642)
							(end 0.2794 0.1778)
						)
						(arc
							(start 0.2794 -0.1778)
							(mid 0.249642 -0.249642)
							(end 0.1778 -0.2794)
						)
					)
					(width 0)
					(fill yes)
				)
			)
		)
	)
	(footprint ""
		(layer "F.Cu")
		(at 83.397852 -102.881176 -90)
		(property "Reference" "R545"
			(at 0 0 270)
			(layer "F.SilkS")
			(hide yes)
			(effects
				(font
					(size 1.27 1.27)
				)
			)
		)
		(property "Value" "0R2J-2-GP"
			(at 0.064008 -3.993896 270)
			(unlocked yes)
			(layer "F.Fab")
			(hide yes)
			(effects
				(font
					(size 1.016 1.016)
					(thickness 0.1524)
				)
			)
		)
		(property "Device Type" "R402H16"
			(at 0.064008 -5.517896 270)
			(unlocked yes)
			(layer "F.Fab")
			(hide yes)
			(effects
				(font
					(size 1.016 1.016)
					(thickness 0.1524)
				)
			)
		)
		(duplicate_pad_numbers_are_jumpers no)
		(fp_line
			(start -0.508 -0.9398)
			(end -0.508 0.9398)
			(stroke
				(width 0.1524)
				(type default)
			)
			(layer "F.SilkS")
		)
		(fp_line
			(start 0.508 -0.9398)
			(end -0.508 -0.9398)
			(stroke
				(width 0.1524)
				(type default)
			)
			(layer "F.SilkS")
		)
		(fp_rect
			(start -0.508 0.9398)
			(end 0.508 -0.9398)
			(stroke
				(width 0)
				(type default)
			)
			(fill no)
			(layer "F.CrtYd")
		)
		(fp_rect
			(start -0.508 0.9398)
			(end 0.508 -0.9398)
			(stroke
				(width 0)
				(type default)
			)
			(fill no)
			(layer "F.Fab")
		)
		(pad "1" smd custom
			(at 0 -0.4445 270)
			(size 0.1397 0.1397)
			(layers "F.Cu" "F.Mask" "F.Paste")
			(net "SCC_FULL_PWR_EN")
			(options
				(clearance outline)
				(anchor circle)
			)
			(primitives
				(gr_poly
					(pts
						(arc
							(start -0.1778 -0.2794)
							(mid -0.249642 -0.249642)
							(end -0.2794 -0.1778)
						)
						(arc
							(start -0.2794 0.1778)
							(mid -0.249642 0.249642)
							(end -0.1778 0.2794)
						)
						(arc
							(start 0.1778 0.2794)
							(mid 0.249642 0.249642)
							(end 0.2794 0.1778)
						)
						(arc
							(start 0.2794 -0.1778)
							(mid 0.249642 -0.249642)
							(end 0.1778 -0.2794)
						)
					)
					(width 0)
					(fill yes)
				)
			)
		)
		(pad "2" smd custom
			(at 0 0.4445 270)
			(size 0.1397 0.1397)
			(layers "F.Cu" "F.Mask" "F.Paste")
			(net "SCC_FULL_PWR_BUF_EN")
			(options
				(clearance outline)
				(anchor circle)
			)
			(primitives
				(gr_poly
					(pts
						(arc
							(start -0.1778 -0.2794)
							(mid -0.249642 -0.249642)
							(end -0.2794 -0.1778)
						)
						(arc
							(start -0.2794 0.1778)
							(mid -0.249642 0.249642)
							(end -0.1778 0.2794)
						)
						(arc
							(start 0.1778 0.2794)
							(mid 0.249642 0.249642)
							(end 0.2794 0.1778)
						)
						(arc
							(start 0.2794 -0.1778)
							(mid 0.249642 -0.249642)
							(end 0.1778 -0.2794)
						)
					)
					(width 0)
					(fill yes)
				)
			)
		)
	)
	(footprint ""
		(layer "F.Cu")
		(at 21.7932 -53.1876 90)
		(property "Reference" "C651"
			(at 0 0 90)
			(layer "F.SilkS")
			(hide yes)
			(effects
				(font
					(size 1.27 1.27)
				)
			)
		)
		(property "Value" "SCD1U50V3KX-GP"
			(at 0 -2.8194 90)
			(unlocked yes)
			(layer "F.Fab")
			(hide yes)
			(effects
				(font
					(size 1.016 1.016)
					(thickness 0.1524)
				)
			)
		)
		(property "Device Type" "C603H36"
			(at 0 -4.3434 90)
			(unlocked yes)
			(layer "F.Fab")
			(hide yes)
			(effects
				(font
					(size 1.016 1.016)
					(thickness 0.1524)
				)
			)
		)
		(duplicate_pad_numbers_are_jumpers no)
		(fp_line
			(start 0.508 0)
			(end -0.508 0)
			(stroke
				(width 0.2032)
				(type default)
			)
			(layer "F.SilkS")
		)
		(fp_rect
			(start -0.5842 1.3335)
			(end 0.5842 -1.3335)
			(stroke
				(width 0)
				(type default)
			)
			(fill no)
			(layer "F.CrtYd")
		)
		(fp_rect
			(start -0.5842 1.3335)
			(end 0.5842 -1.3335)
			(stroke
				(width 0)
				(type default)
			)
			(fill no)
			(layer "F.Fab")
		)
		(pad "1" smd custom
			(at 0 -0.762 90)
			(size 0.2159 0.2159)
			(layers "F.Cu" "F.Mask" "F.Paste")
			(net "MB0_ISET_R")
			(options
				(clearance outline)
				(anchor circle)
			)
			(primitives
				(gr_poly
					(pts
						(arc
							(start -0.3302 -0.4318)
							(mid -0.402042 -0.402042)
							(end -0.4318 -0.3302)
						)
						(arc
							(start -0.4318 0.3302)
							(mid -0.402042 0.402042)
							(end -0.3302 0.4318)
						)
						(arc
							(start 0.3302 0.4318)
							(mid 0.402042 0.402042)
							(end 0.4318 0.3302)
						)
						(arc
							(start 0.4318 -0.3302)
							(mid 0.402042 -0.402042)
							(end 0.3302 -0.4318)
						)
					)
					(width 0)
					(fill yes)
				)
			)
		)
		(pad "2" smd custom
			(at 0 0.762 90)
			(size 0.2159 0.2159)
			(layers "F.Cu" "F.Mask" "F.Paste")
			(net "AGND_CURRENT_MON")
			(options
				(clearance outline)
				(anchor circle)
			)
			(primitives
				(gr_poly
					(pts
						(arc
							(start -0.3302 -0.4318)
							(mid -0.402042 -0.402042)
							(end -0.4318 -0.3302)
						)
						(arc
							(start -0.4318 0.3302)
							(mid -0.402042 0.402042)
							(end -0.3302 0.4318)
						)
						(arc
							(start 0.3302 0.4318)
							(mid 0.402042 0.402042)
							(end 0.4318 0.3302)
						)
						(arc
							(start 0.4318 -0.3302)
							(mid 0.402042 -0.402042)
							(end 0.3302 -0.4318)
						)
					)
					(width 0)
					(fill yes)
				)
			)
		)
	)
	(footprint ""
		(layer "F.Cu")
		(at 154.612594 -71.60387)
		(property "Reference" "R328"
			(at 0 0 0)
			(layer "F.SilkS")
			(hide yes)
			(effects
				(font
					(size 1.27 1.27)
				)
			)
		)
		(property "Value" "0R2J-2-GP"
			(at 0.064008 -3.993896 0)
			(unlocked yes)
			(layer "F.Fab")
			(hide yes)
			(effects
				(font
					(size 1.016 1.016)
					(thickness 0.1524)
				)
			)
		)
		(property "Device Type" "R402H16"
			(at 0.064008 -5.517896 0)
			(unlocked yes)
			(layer "F.Fab")
			(hide yes)
			(effects
				(font
					(size 1.016 1.016)
					(thickness 0.1524)
				)
			)
		)
		(duplicate_pad_numbers_are_jumpers no)
		(fp_line
			(start -0.508 -0.9398)
			(end -0.508 0.9398)
			(stroke
				(width 0.1524)
				(type default)
			)
			(layer "F.SilkS")
		)
		(fp_line
			(start 0.508 -0.9398)
			(end -0.508 -0.9398)
			(stroke
				(width 0.1524)
				(type default)
			)
			(layer "F.SilkS")
		)
		(fp_rect
			(start -0.508 0.9398)
			(end 0.508 -0.9398)
			(stroke
				(width 0)
				(type default)
			)
			(fill no)
			(layer "F.CrtYd")
		)
		(fp_rect
			(start -0.508 0.9398)
			(end 0.508 -0.9398)
			(stroke
				(width 0)
				(type default)
			)
			(fill no)
			(layer "F.Fab")
		)
		(pad "1" smd custom
			(at 0 -0.4445)
			(size 0.1397 0.1397)
			(layers "F.Cu" "F.Mask" "F.Paste")
			(net "VOL_SEN2_SDA")
			(options
				(clearance outline)
				(anchor circle)
			)
			(primitives
				(gr_poly
					(pts
						(arc
							(start -0.1778 -0.2794)
							(mid -0.249642 -0.249642)
							(end -0.2794 -0.1778)
						)
						(arc
							(start -0.2794 0.1778)
							(mid -0.249642 0.249642)
							(end -0.1778 0.2794)
						)
						(arc
							(start 0.1778 0.2794)
							(mid 0.249642 0.249642)
							(end 0.2794 0.1778)
						)
						(arc
							(start 0.2794 -0.1778)
							(mid 0.249642 -0.249642)
							(end 0.1778 -0.2794)
						)
					)
					(width 0)
					(fill yes)
				)
			)
		)
		(pad "2" smd custom
			(at 0 0.4445)
			(size 0.1397 0.1397)
			(layers "F.Cu" "F.Mask" "F.Paste")
			(net "I2C_SCC_SDA2")
			(options
				(clearance outline)
				(anchor circle)
			)
			(primitives
				(gr_poly
					(pts
						(arc
							(start -0.1778 -0.2794)
							(mid -0.249642 -0.249642)
							(end -0.2794 -0.1778)
						)
						(arc
							(start -0.2794 0.1778)
							(mid -0.249642 0.249642)
							(end -0.1778 0.2794)
						)
						(arc
							(start 0.1778 0.2794)
							(mid 0.249642 0.249642)
							(end 0.2794 0.1778)
						)
						(arc
							(start 0.2794 -0.1778)
							(mid 0.249642 -0.249642)
							(end 0.1778 -0.2794)
						)
					)
					(width 0)
					(fill yes)
				)
			)
		)
	)
	(footprint ""
		(layer "F.Cu")
		(at 176.36871 -23.547832 90)
		(property "Reference" "VIA6"
			(at 0 0 90)
			(layer "F.SilkS")
			(hide yes)
			(effects
				(font
					(size 1.27 1.27)
				)
			)
		)
		(property "Value" "85OHM-8L-1D6MM-L16L18-GP"
			(at 4.064 0.6096 90)
			(unlocked yes)
			(layer "F.Fab")
			(hide yes)
			(effects
				(font
					(size 1.016 1.016)
					(thickness 0.1524)
				)
			)
		)
		(property "Device Type" "VIA-PCIE-4P-368076"
			(at 4.064 -0.9144 90)
			(unlocked yes)
			(layer "F.Fab")
			(hide yes)
			(effects
				(font
					(size 1.016 1.016)
					(thickness 0.1524)
				)
			)
		)
		(duplicate_pad_numbers_are_jumpers no)
		(fp_rect
			(start -1.8415 0.381)
			(end 1.8415 -0.381)
			(stroke
				(width 0)
				(type default)
			)
			(fill no)
			(layer "F.CrtYd")
		)
		(fp_rect
			(start -1.8415 0.381)
			(end 1.8415 -0.381)
			(stroke
				(width 0)
				(type default)
			)
			(fill no)
			(layer "F.Fab")
		)
		(pad "1" thru_hole circle
			(at -1.4605 0 90)
			(size 0.508 0.508)
			(drill 0.254)
			(layers "*.Cu" "*.Mask")
			(remove_unused_layers no)
			(net "GND")
			(clearance 0.127)
			(thermal_gap 0.127)
		)
		(pad "2" thru_hole circle
			(at -0.4445 0 90)
			(size 0.508 0.508)
			(drill 0.254)
			(layers "*.Cu" "*.Mask")
			(remove_unused_layers no)
			(net "PCIE_COMP_TO_SCC_5_DP")
			(clearance 0.127)
			(thermal_gap 0.127)
		)
		(pad "3" thru_hole circle
			(at 0.4445 0 90)
			(size 0.508 0.508)
			(drill 0.254)
			(layers "*.Cu" "*.Mask")
			(remove_unused_layers no)
			(net "PCIE_COMP_TO_SCC_5_DN")
			(clearance 0.127)
			(thermal_gap 0.127)
		)
		(pad "4" thru_hole circle
			(at 1.4605 0 90)
			(size 0.508 0.508)
			(drill 0.254)
			(layers "*.Cu" "*.Mask")
			(remove_unused_layers no)
			(net "GND")
			(clearance 0.127)
			(thermal_gap 0.127)
		)
	)
	(footprint ""
		(layer "F.Cu")
		(at 43.6372 -29.083 90)
		(property "Reference" "R398"
			(at 0 0 90)
			(layer "F.SilkS")
			(hide yes)
			(effects
				(font
					(size 1.27 1.27)
				)
			)
		)
		(property "Value" "10KR2F-2-GP"
			(at 0.064008 -3.993896 90)
			(unlocked yes)
			(layer "F.Fab")
			(hide yes)
			(effects
				(font
					(size 1.016 1.016)
					(thickness 0.1524)
				)
			)
		)
		(property "Device Type" "R402H16"
			(at 0.064008 -5.517896 90)
			(unlocked yes)
			(layer "F.Fab")
			(hide yes)
			(effects
				(font
					(size 1.016 1.016)
					(thickness 0.1524)
				)
			)
		)
		(duplicate_pad_numbers_are_jumpers no)
		(fp_line
			(start 0.508 -0.9398)
			(end -0.508 -0.9398)
			(stroke
				(width 0.1524)
				(type default)
			)
			(layer "F.SilkS")
		)
		(fp_line
			(start -0.508 -0.9398)
			(end -0.508 0.9398)
			(stroke
				(width 0.1524)
				(type default)
			)
			(layer "F.SilkS")
		)
		(fp_rect
			(start -0.508 0.9398)
			(end 0.508 -0.9398)
			(stroke
				(width 0)
				(type default)
			)
			(fill no)
			(layer "F.CrtYd")
		)
		(fp_rect
			(start -0.508 0.9398)
			(end 0.508 -0.9398)
			(stroke
				(width 0)
				(type default)
			)
			(fill no)
			(layer "F.Fab")
		)
		(pad "1" smd custom
			(at 0 -0.4445 90)
			(size 0.1397 0.1397)
			(layers "F.Cu" "F.Mask" "F.Paste")
			(net "P0V9_VREF")
			(options
				(clearance outline)
				(anchor circle)
			)
			(primitives
				(gr_poly
					(pts
						(arc
							(start -0.1778 -0.2794)
							(mid -0.249642 -0.249642)
							(end -0.2794 -0.1778)
						)
						(arc
							(start -0.2794 0.1778)
							(mid -0.249642 0.249642)
							(end -0.1778 0.2794)
						)
						(arc
							(start 0.1778 0.2794)
							(mid 0.249642 0.249642)
							(end 0.2794 0.1778)
						)
						(arc
							(start 0.2794 -0.1778)
							(mid 0.249642 -0.249642)
							(end 0.1778 -0.2794)
						)
					)
					(width 0)
					(fill yes)
				)
			)
		)
		(pad "2" smd custom
			(at 0 0.4445 90)
			(size 0.1397 0.1397)
			(layers "F.Cu" "F.Mask" "F.Paste")
			(net "P0V9_REFIN")
			(options
				(clearance outline)
				(anchor circle)
			)
			(primitives
				(gr_poly
					(pts
						(arc
							(start -0.1778 -0.2794)
							(mid -0.249642 -0.249642)
							(end -0.2794 -0.1778)
						)
						(arc
							(start -0.2794 0.1778)
							(mid -0.249642 0.249642)
							(end -0.1778 0.2794)
						)
						(arc
							(start 0.1778 0.2794)
							(mid 0.249642 0.249642)
							(end 0.2794 0.1778)
						)
						(arc
							(start 0.2794 -0.1778)
							(mid 0.249642 -0.249642)
							(end 0.1778 -0.2794)
						)
					)
					(width 0)
					(fill yes)
				)
			)
		)
	)
	(footprint ""
		(layer "F.Cu")
		(at 134.339076 -88.72601)
		(property "Reference" "R68"
			(at 0 0 0)
			(layer "F.SilkS")
			(hide yes)
			(effects
				(font
					(size 1.27 1.27)
				)
			)
		)
		(property "Value" "1KR2F-3-GP"
			(at 0.064008 -3.993896 0)
			(unlocked yes)
			(layer "F.Fab")
			(hide yes)
			(effects
				(font
					(size 1.016 1.016)
					(thickness 0.1524)
				)
			)
		)
		(property "Device Type" "R402H16"
			(at 0.064008 -5.517896 0)
			(unlocked yes)
			(layer "F.Fab")
			(hide yes)
			(effects
				(font
					(size 1.016 1.016)
					(thickness 0.1524)
				)
			)
		)
		(duplicate_pad_numbers_are_jumpers no)
		(fp_line
			(start -0.508 -0.9398)
			(end -0.508 0.9398)
			(stroke
				(width 0.1524)
				(type default)
			)
			(layer "F.SilkS")
		)
		(fp_line
			(start 0.508 -0.9398)
			(end -0.508 -0.9398)
			(stroke
				(width 0.1524)
				(type default)
			)
			(layer "F.SilkS")
		)
		(fp_rect
			(start -0.508 0.9398)
			(end 0.508 -0.9398)
			(stroke
				(width 0)
				(type default)
			)
			(fill no)
			(layer "F.CrtYd")
		)
		(fp_rect
			(start -0.508 0.9398)
			(end 0.508 -0.9398)
			(stroke
				(width 0)
				(type default)
			)
			(fill no)
			(layer "F.Fab")
		)
		(pad "1" smd custom
			(at 0 -0.4445)
			(size 0.1397 0.1397)
			(layers "F.Cu" "F.Mask" "F.Paste")
			(net "P1V8_E")
			(options
				(clearance outline)
				(anchor circle)
			)
			(primitives
				(gr_poly
					(pts
						(arc
							(start -0.1778 -0.2794)
							(mid -0.249642 -0.249642)
							(end -0.2794 -0.1778)
						)
						(arc
							(start -0.2794 0.1778)
							(mid -0.249642 0.249642)
							(end -0.1778 0.2794)
						)
						(arc
							(start 0.1778 0.2794)
							(mid 0.249642 0.249642)
							(end 0.2794 0.1778)
						)
						(arc
							(start 0.2794 -0.1778)
							(mid 0.249642 -0.249642)
							(end 0.1778 -0.2794)
						)
					)
					(width 0)
					(fill yes)
				)
			)
		)
		(pad "2" smd custom
			(at 0 0.4445)
			(size 0.1397 0.1397)
			(layers "F.Cu" "F.Mask" "F.Paste")
			(net "EXP_I2C_SCL10")
			(options
				(clearance outline)
				(anchor circle)
			)
			(primitives
				(gr_poly
					(pts
						(arc
							(start -0.1778 -0.2794)
							(mid -0.249642 -0.249642)
							(end -0.2794 -0.1778)
						)
						(arc
							(start -0.2794 0.1778)
							(mid -0.249642 0.249642)
							(end -0.1778 0.2794)
						)
						(arc
							(start 0.1778 0.2794)
							(mid 0.249642 0.249642)
							(end 0.2794 0.1778)
						)
						(arc
							(start 0.2794 -0.1778)
							(mid 0.249642 -0.249642)
							(end 0.1778 -0.2794)
						)
					)
					(width 0)
					(fill yes)
				)
			)
		)
	)
)
